(kicad_pcb
	(version 20260206)
	(generator "pcbnew")
	(generator_version "10.0")
	(general
		(thickness 1.6)
		(legacy_teardrops no)
	)
	(paper "A4")
	(title_block
		(title "04192023_DAF0TMB3IC0_F0TG_MB_C_brd_V02_OCP.brd")
		(comment 1 "Grand Teton / footprints 900-905 of 8354")
	)
	(layers
		(0 "F.Cu" signal "TOP")
		(4 "In1.Cu" signal "GND")
		(6 "In2.Cu" signal "IN1")
		(8 "In3.Cu" signal "GND1")
		(10 "In4.Cu" signal "IN2")
		(12 "In5.Cu" signal "GND2")
		(14 "In6.Cu" signal "IN3")
		(16 "In7.Cu" signal "GND3")
		(18 "In8.Cu" signal "VCC")
		(20 "In9.Cu" signal "VCC1")
		(22 "In10.Cu" signal "GND4")
		(24 "In11.Cu" signal "IN4")
		(26 "In12.Cu" signal "GND5")
		(28 "In13.Cu" signal "IN5")
		(30 "In14.Cu" signal "GND6")
		(32 "In15.Cu" signal "IN6")
		(34 "In16.Cu" signal "GND7")
		(2 "B.Cu" signal "BOTTOM")
		(9 "F.Adhes" user "F.Adhesive")
		(11 "B.Adhes" user "B.Adhesive")
		(13 "F.Paste" user "Package Geometry/Pastemask Top")
		(15 "B.Paste" user "Package Geometry/Pastemask Bottom")
		(5 "F.SilkS" user "Ref Des/Silkscreen Top")
		(7 "B.SilkS" user "Ref Des/Silkscreen Bottom")
		(1 "F.Mask" user "Board Geometry/Soldermask Top")
		(3 "B.Mask" user "Board Geometry/Soldermask Bottom")
		(17 "Dwgs.User" user "User.Drawings")
		(19 "Cmts.User" user "User.Comments")
		(21 "Eco1.User" user "User.Eco1")
		(23 "Eco2.User" user "User.Eco2")
		(25 "Edge.Cuts" user "Board Geometry/Outline")
		(27 "Margin" user)
		(31 "F.CrtYd" user "Package Geometry/Place Bound Top")
		(29 "B.CrtYd" user "Package Geometry/Place Bound Bottom")
		(35 "F.Fab" user "Ref Des/Assembly Top")
		(33 "B.Fab" user "Ref Des/Assembly Bottom")
	)
	(footprint ""
		(layer "F.Cu")
		(at 437.221376 -16.244824 -90)
		(property "Reference" "R39"
			(at 0 0 270)
			(layer "F.SilkS")
			(hide yes)
			(effects
				(font
					(size 1.27 1.27)
				)
			)
		)
		(property "Value" ""
			(at 0 0 270)
			(layer "F.Fab")
			(effects
				(font
					(size 1.27 1.27)
				)
			)
		)
		(duplicate_pad_numbers_are_jumpers no)
		(fp_line
			(start -0.7874 0.4064)
			(end -0.7874 -0.4064)
			(stroke
				(width 0.1524)
				(type default)
			)
			(layer "F.SilkS")
		)
		(fp_line
			(start 0.7874 0.4064)
			(end -0.7874 0.4064)
			(stroke
				(width 0.1524)
				(type default)
			)
			(layer "F.SilkS")
		)
		(fp_line
			(start -0.7874 -0.4064)
			(end 0.7874 -0.4064)
			(stroke
				(width 0.1524)
				(type default)
			)
			(layer "F.SilkS")
		)
		(fp_line
			(start 0.7874 -0.4064)
			(end 0.7874 0.4064)
			(stroke
				(width 0.1524)
				(type default)
			)
			(layer "F.SilkS")
		)
		(fp_line
			(start -0.67945 0.3048)
			(end -0.67945 -0.305054)
			(stroke
				(width 0.1)
				(type default)
			)
			(layer "F.Fab")
		)
		(fp_line
			(start -0.12065 0.3048)
			(end -0.67945 0.3048)
			(stroke
				(width 0.1)
				(type default)
			)
			(layer "F.Fab")
		)
		(fp_line
			(start 0.120396 0.3048)
			(end 0.120396 0.2794)
			(stroke
				(width 0.1)
				(type default)
			)
			(layer "F.Fab")
		)
		(fp_line
			(start 0.67945 0.3048)
			(end 0.120396 0.3048)
			(stroke
				(width 0.1)
				(type default)
			)
			(layer "F.Fab")
		)
		(fp_line
			(start -0.12065 0.2794)
			(end -0.12065 0.3048)
			(stroke
				(width 0.1)
				(type default)
			)
			(layer "F.Fab")
		)
		(fp_line
			(start 0.120396 0.2794)
			(end -0.12065 0.2794)
			(stroke
				(width 0.1)
				(type default)
			)
			(layer "F.Fab")
		)
		(fp_line
			(start -0.12065 -0.2794)
			(end 0.12065 -0.2794)
			(stroke
				(width 0.1)
				(type default)
			)
			(layer "F.Fab")
		)
		(fp_line
			(start 0.12065 -0.2794)
			(end 0.12065 -0.3048)
			(stroke
				(width 0.1)
				(type default)
			)
			(layer "F.Fab")
		)
		(fp_line
			(start 0.12065 -0.3048)
			(end 0.67945 -0.3048)
			(stroke
				(width 0.1)
				(type default)
			)
			(layer "F.Fab")
		)
		(fp_line
			(start 0.67945 -0.3048)
			(end 0.67945 0.3048)
			(stroke
				(width 0.1)
				(type default)
			)
			(layer "F.Fab")
		)
		(fp_line
			(start -0.67945 -0.305054)
			(end -0.12065 -0.305054)
			(stroke
				(width 0.1)
				(type default)
			)
			(layer "F.Fab")
		)
		(fp_line
			(start -0.12065 -0.305054)
			(end -0.12065 -0.2794)
			(stroke
				(width 0.1)
				(type default)
			)
			(layer "F.Fab")
		)
		(pad "1" smd circle
			(at -0.40005 0 270)
			(size 0 0)
			(layers "F.Cu" "F.Mask" "F.Paste")
			(net "OCP_SFF_ISO_BIF0_EN")
		)
		(pad "2" smd circle
			(at 0.40005 0 270)
			(size 0 0)
			(layers "F.Cu" "F.Mask" "F.Paste")
			(net "OCP_SFF_BIF0_R_N")
		)
	)
	(footprint ""
		(layer "F.Cu")
		(at 329.360022 -36.001706 180)
		(property "Reference" "R1792"
			(at 0 0 180)
			(layer "F.SilkS")
			(hide yes)
			(effects
				(font
					(size 1.27 1.27)
				)
			)
		)
		(property "Value" ""
			(at 0 0 180)
			(layer "F.Fab")
			(effects
				(font
					(size 1.27 1.27)
				)
			)
		)
		(duplicate_pad_numbers_are_jumpers no)
		(fp_line
			(start 0.7874 0.4064)
			(end -0.7874 0.4064)
			(stroke
				(width 0.1524)
				(type default)
			)
			(layer "F.SilkS")
		)
		(fp_line
			(start 0.7874 -0.4064)
			(end 0.7874 0.4064)
			(stroke
				(width 0.1524)
				(type default)
			)
			(layer "F.SilkS")
		)
		(fp_line
			(start -0.7874 0.4064)
			(end -0.7874 -0.4064)
			(stroke
				(width 0.1524)
				(type default)
			)
			(layer "F.SilkS")
		)
		(fp_line
			(start -0.7874 -0.4064)
			(end 0.7874 -0.4064)
			(stroke
				(width 0.1524)
				(type default)
			)
			(layer "F.SilkS")
		)
		(fp_line
			(start 0.67945 0.3048)
			(end 0.120396 0.3048)
			(stroke
				(width 0.1)
				(type default)
			)
			(layer "F.Fab")
		)
		(fp_line
			(start 0.67945 -0.3048)
			(end 0.67945 0.3048)
			(stroke
				(width 0.1)
				(type default)
			)
			(layer "F.Fab")
		)
		(fp_line
			(start 0.12065 -0.2794)
			(end 0.12065 -0.3048)
			(stroke
				(width 0.1)
				(type default)
			)
			(layer "F.Fab")
		)
		(fp_line
			(start 0.12065 -0.3048)
			(end 0.67945 -0.3048)
			(stroke
				(width 0.1)
				(type default)
			)
			(layer "F.Fab")
		)
		(fp_line
			(start 0.120396 0.3048)
			(end 0.120396 0.2794)
			(stroke
				(width 0.1)
				(type default)
			)
			(layer "F.Fab")
		)
		(fp_line
			(start 0.120396 0.2794)
			(end -0.12065 0.2794)
			(stroke
				(width 0.1)
				(type default)
			)
			(layer "F.Fab")
		)
		(fp_line
			(start -0.12065 0.3048)
			(end -0.67945 0.3048)
			(stroke
				(width 0.1)
				(type default)
			)
			(layer "F.Fab")
		)
		(fp_line
			(start -0.12065 0.2794)
			(end -0.12065 0.3048)
			(stroke
				(width 0.1)
				(type default)
			)
			(layer "F.Fab")
		)
		(fp_line
			(start -0.12065 -0.2794)
			(end 0.12065 -0.2794)
			(stroke
				(width 0.1)
				(type default)
			)
			(layer "F.Fab")
		)
		(fp_line
			(start -0.12065 -0.305054)
			(end -0.12065 -0.2794)
			(stroke
				(width 0.1)
				(type default)
			)
			(layer "F.Fab")
		)
		(fp_line
			(start -0.67945 0.3048)
			(end -0.67945 -0.305054)
			(stroke
				(width 0.1)
				(type default)
			)
			(layer "F.Fab")
		)
		(fp_line
			(start -0.67945 -0.305054)
			(end -0.12065 -0.305054)
			(stroke
				(width 0.1)
				(type default)
			)
			(layer "F.Fab")
		)
		(pad "1" smd circle
			(at -0.40005 0 180)
			(size 0 0)
			(layers "F.Cu" "F.Mask" "F.Paste")
			(net "SMB_SCM_2_R4_SDA")
		)
		(pad "2" smd circle
			(at 0.40005 0 180)
			(size 0 0)
			(layers "F.Cu" "F.Mask" "F.Paste")
			(net "SMB_SEN_MAM_3V3AUX_SDA")
		)
	)
	(footprint ""
		(layer "F.Cu")
		(at 371.272308 -424.024552 -90)
		(property "Reference" "R4190"
			(at 0 0 270)
			(layer "F.SilkS")
			(hide yes)
			(effects
				(font
					(size 1.27 1.27)
				)
			)
		)
		(property "Value" ""
			(at 0 0 270)
			(layer "F.Fab")
			(effects
				(font
					(size 1.27 1.27)
				)
			)
		)
		(duplicate_pad_numbers_are_jumpers no)
		(fp_line
			(start -0.7874 0.4064)
			(end -0.7874 -0.4064)
			(stroke
				(width 0.1524)
				(type default)
			)
			(layer "F.SilkS")
		)
		(fp_line
			(start 0.7874 0.4064)
			(end -0.7874 0.4064)
			(stroke
				(width 0.1524)
				(type default)
			)
			(layer "F.SilkS")
		)
		(fp_line
			(start -0.7874 -0.4064)
			(end 0.7874 -0.4064)
			(stroke
				(width 0.1524)
				(type default)
			)
			(layer "F.SilkS")
		)
		(fp_line
			(start 0.7874 -0.4064)
			(end 0.7874 0.4064)
			(stroke
				(width 0.1524)
				(type default)
			)
			(layer "F.SilkS")
		)
		(fp_line
			(start -0.67945 0.3048)
			(end -0.67945 -0.305054)
			(stroke
				(width 0.1)
				(type default)
			)
			(layer "F.Fab")
		)
		(fp_line
			(start -0.12065 0.3048)
			(end -0.67945 0.3048)
			(stroke
				(width 0.1)
				(type default)
			)
			(layer "F.Fab")
		)
		(fp_line
			(start 0.120396 0.3048)
			(end 0.120396 0.2794)
			(stroke
				(width 0.1)
				(type default)
			)
			(layer "F.Fab")
		)
		(fp_line
			(start 0.67945 0.3048)
			(end 0.120396 0.3048)
			(stroke
				(width 0.1)
				(type default)
			)
			(layer "F.Fab")
		)
		(fp_line
			(start -0.12065 0.2794)
			(end -0.12065 0.3048)
			(stroke
				(width 0.1)
				(type default)
			)
			(layer "F.Fab")
		)
		(fp_line
			(start 0.120396 0.2794)
			(end -0.12065 0.2794)
			(stroke
				(width 0.1)
				(type default)
			)
			(layer "F.Fab")
		)
		(fp_line
			(start -0.12065 -0.2794)
			(end 0.12065 -0.2794)
			(stroke
				(width 0.1)
				(type default)
			)
			(layer "F.Fab")
		)
		(fp_line
			(start 0.12065 -0.2794)
			(end 0.12065 -0.3048)
			(stroke
				(width 0.1)
				(type default)
			)
			(layer "F.Fab")
		)
		(fp_line
			(start 0.12065 -0.3048)
			(end 0.67945 -0.3048)
			(stroke
				(width 0.1)
				(type default)
			)
			(layer "F.Fab")
		)
		(fp_line
			(start 0.67945 -0.3048)
			(end 0.67945 0.3048)
			(stroke
				(width 0.1)
				(type default)
			)
			(layer "F.Fab")
		)
		(fp_line
			(start -0.67945 -0.305054)
			(end -0.12065 -0.305054)
			(stroke
				(width 0.1)
				(type default)
			)
			(layer "F.Fab")
		)
		(fp_line
			(start -0.12065 -0.305054)
			(end -0.12065 -0.2794)
			(stroke
				(width 0.1)
				(type default)
			)
			(layer "F.Fab")
		)
		(pad "1" smd circle
			(at -0.40005 0 270)
			(size 0 0)
			(layers "F.Cu" "F.Mask" "F.Paste")
			(net "P3V3_AUX")
		)
		(pad "2" smd circle
			(at 0.40005 0 270)
			(size 0 0)
			(layers "F.Cu" "F.Mask" "F.Paste")
			(net "U270_0_ADD2")
		)
	)
	(footprint ""
		(layer "F.Cu")
		(at 366.534446 -28.306522 90)
		(property "Reference" "R824"
			(at 0 0 90)
			(layer "F.SilkS")
			(hide yes)
			(effects
				(font
					(size 1.27 1.27)
				)
			)
		)
		(property "Value" ""
			(at 0 0 90)
			(layer "F.Fab")
			(effects
				(font
					(size 1.27 1.27)
				)
			)
		)
		(duplicate_pad_numbers_are_jumpers no)
		(fp_line
			(start 0.7874 -0.4064)
			(end 0.7874 0.4064)
			(stroke
				(width 0.1524)
				(type default)
			)
			(layer "F.SilkS")
		)
		(fp_line
			(start -0.7874 -0.4064)
			(end 0.7874 -0.4064)
			(stroke
				(width 0.1524)
				(type default)
			)
			(layer "F.SilkS")
		)
		(fp_line
			(start 0.7874 0.4064)
			(end -0.7874 0.4064)
			(stroke
				(width 0.1524)
				(type default)
			)
			(layer "F.SilkS")
		)
		(fp_line
			(start -0.7874 0.4064)
			(end -0.7874 -0.4064)
			(stroke
				(width 0.1524)
				(type default)
			)
			(layer "F.SilkS")
		)
		(fp_line
			(start -0.12065 -0.305054)
			(end -0.12065 -0.2794)
			(stroke
				(width 0.1)
				(type default)
			)
			(layer "F.Fab")
		)
		(fp_line
			(start -0.67945 -0.305054)
			(end -0.12065 -0.305054)
			(stroke
				(width 0.1)
				(type default)
			)
			(layer "F.Fab")
		)
		(fp_line
			(start 0.67945 -0.3048)
			(end 0.67945 0.3048)
			(stroke
				(width 0.1)
				(type default)
			)
			(layer "F.Fab")
		)
		(fp_line
			(start 0.12065 -0.3048)
			(end 0.67945 -0.3048)
			(stroke
				(width 0.1)
				(type default)
			)
			(layer "F.Fab")
		)
		(fp_line
			(start 0.12065 -0.2794)
			(end 0.12065 -0.3048)
			(stroke
				(width 0.1)
				(type default)
			)
			(layer "F.Fab")
		)
		(fp_line
			(start -0.12065 -0.2794)
			(end 0.12065 -0.2794)
			(stroke
				(width 0.1)
				(type default)
			)
			(layer "F.Fab")
		)
		(fp_line
			(start 0.120396 0.2794)
			(end -0.12065 0.2794)
			(stroke
				(width 0.1)
				(type default)
			)
			(layer "F.Fab")
		)
		(fp_line
			(start -0.12065 0.2794)
			(end -0.12065 0.3048)
			(stroke
				(width 0.1)
				(type default)
			)
			(layer "F.Fab")
		)
		(fp_line
			(start 0.67945 0.3048)
			(end 0.120396 0.3048)
			(stroke
				(width 0.1)
				(type default)
			)
			(layer "F.Fab")
		)
		(fp_line
			(start 0.120396 0.3048)
			(end 0.120396 0.2794)
			(stroke
				(width 0.1)
				(type default)
			)
			(layer "F.Fab")
		)
		(fp_line
			(start -0.12065 0.3048)
			(end -0.67945 0.3048)
			(stroke
				(width 0.1)
				(type default)
			)
			(layer "F.Fab")
		)
		(fp_line
			(start -0.67945 0.3048)
			(end -0.67945 -0.305054)
			(stroke
				(width 0.1)
				(type default)
			)
			(layer "F.Fab")
		)
		(pad "1" smd circle
			(at -0.40005 0 90)
			(size 0 0)
			(layers "F.Cu" "F.Mask" "F.Paste")
			(net "P3V3_AUX")
		)
		(pad "2" smd circle
			(at 0.40005 0 90)
			(size 0 0)
			(layers "F.Cu" "F.Mask" "F.Paste")
			(net "UART_CPU0_LVC3_UART0_TX")
		)
	)
	(footprint ""
		(layer "F.Cu")
		(at 435.628288 -351.22866 -90)
		(property "Reference" "PC210_2"
			(at 0 0 270)
			(layer "F.SilkS")
			(hide yes)
			(effects
				(font
					(size 1.27 1.27)
				)
			)
		)
		(property "Value" ""
			(at 0 0 270)
			(layer "F.Fab")
			(effects
				(font
					(size 1.27 1.27)
				)
			)
		)
		(duplicate_pad_numbers_are_jumpers no)
		(fp_line
			(start -0.7874 0.4064)
			(end -0.7874 -0.4064)
			(stroke
				(width 0.1524)
				(type default)
			)
			(layer "F.SilkS")
		)
		(fp_line
			(start 0.7874 0.4064)
			(end -0.7874 0.4064)
			(stroke
				(width 0.1524)
				(type default)
			)
			(layer "F.SilkS")
		)
		(fp_line
			(start -0.7874 -0.4064)
			(end 0.7874 -0.4064)
			(stroke
				(width 0.1524)
				(type default)
			)
			(layer "F.SilkS")
		)
		(fp_line
			(start 0.7874 -0.4064)
			(end 0.7874 0.4064)
			(stroke
				(width 0.1524)
				(type default)
			)
			(layer "F.SilkS")
		)
		(fp_line
			(start -0.67945 0.3048)
			(end -0.67945 -0.305054)
			(stroke
				(width 0.1)
				(type default)
			)
			(layer "F.Fab")
		)
		(fp_line
			(start -0.12065 0.3048)
			(end -0.67945 0.3048)
			(stroke
				(width 0.1)
				(type default)
			)
			(layer "F.Fab")
		)
		(fp_line
			(start 0.120396 0.3048)
			(end 0.120396 0.2794)
			(stroke
				(width 0.1)
				(type default)
			)
			(layer "F.Fab")
		)
		(fp_line
			(start 0.67945 0.3048)
			(end 0.120396 0.3048)
			(stroke
				(width 0.1)
				(type default)
			)
			(layer "F.Fab")
		)
		(fp_line
			(start -0.12065 0.2794)
			(end -0.12065 0.3048)
			(stroke
				(width 0.1)
				(type default)
			)
			(layer "F.Fab")
		)
		(fp_line
			(start 0.120396 0.2794)
			(end -0.12065 0.2794)
			(stroke
				(width 0.1)
				(type default)
			)
			(layer "F.Fab")
		)
		(fp_line
			(start -0.12065 -0.2794)
			(end 0.12065 -0.2794)
			(stroke
				(width 0.1)
				(type default)
			)
			(layer "F.Fab")
		)
		(fp_line
			(start 0.12065 -0.2794)
			(end 0.12065 -0.3048)
			(stroke
				(width 0.1)
				(type default)
			)
			(layer "F.Fab")
		)
		(fp_line
			(start 0.12065 -0.3048)
			(end 0.67945 -0.3048)
			(stroke
				(width 0.1)
				(type default)
			)
			(layer "F.Fab")
		)
		(fp_line
			(start 0.67945 -0.3048)
			(end 0.67945 0.3048)
			(stroke
				(width 0.1)
				(type default)
			)
			(layer "F.Fab")
		)
		(fp_line
			(start -0.67945 -0.305054)
			(end -0.12065 -0.305054)
			(stroke
				(width 0.1)
				(type default)
			)
			(layer "F.Fab")
		)
		(fp_line
			(start -0.12065 -0.305054)
			(end -0.12065 -0.2794)
			(stroke
				(width 0.1)
				(type default)
			)
			(layer "F.Fab")
		)
		(pad "1" smd circle
			(at -0.40005 0 270)
			(size 0 0)
			(layers "F.Cu" "F.Mask" "F.Paste")
			(net "SW_P12V_AUX_PVDD11_S3_P0_FLT")
		)
		(pad "2" smd circle
			(at 0.40005 0 270)
			(size 0 0)
			(layers "F.Cu" "F.Mask" "F.Paste")
			(net "GND")
		)
	)
	(footprint ""
		(layer "F.Cu")
		(at 449.531232 -425.210478)
		(property "Reference" "PC6601"
			(at 0 0 0)
			(layer "F.SilkS")
			(hide yes)
			(effects
				(font
					(size 1.27 1.27)
				)
			)
		)
		(property "Value" ""
			(at 0 0 0)
			(layer "F.Fab")
			(effects
				(font
					(size 1.27 1.27)
				)
			)
		)
		(duplicate_pad_numbers_are_jumpers no)
		(fp_line
			(start -0.7874 -0.4064)
			(end 0.7874 -0.4064)
			(stroke
				(width 0.1524)
				(type default)
			)
			(layer "F.SilkS")
		)
		(fp_line
			(start -0.7874 0.4064)
			(end -0.7874 -0.4064)
			(stroke
				(width 0.1524)
				(type default)
			)
			(layer "F.SilkS")
		)
		(fp_line
			(start 0.7874 -0.4064)
			(end 0.7874 0.4064)
			(stroke
				(width 0.1524)
				(type default)
			)
			(layer "F.SilkS")
		)
		(fp_line
			(start 0.7874 0.4064)
			(end -0.7874 0.4064)
			(stroke
				(width 0.1524)
				(type default)
			)
			(layer "F.SilkS")
		)
		(fp_line
			(start -0.67945 -0.305054)
			(end -0.12065 -0.305054)
			(stroke
				(width 0.1)
				(type default)
			)
			(layer "F.Fab")
		)
		(fp_line
			(start -0.67945 0.3048)
			(end -0.67945 -0.305054)
			(stroke
				(width 0.1)
				(type default)
			)
			(layer "F.Fab")
		)
		(fp_line
			(start -0.12065 -0.305054)
			(end -0.12065 -0.2794)
			(stroke
				(width 0.1)
				(type default)
			)
			(layer "F.Fab")
		)
		(fp_line
			(start -0.12065 -0.2794)
			(end 0.12065 -0.2794)
			(stroke
				(width 0.1)
				(type default)
			)
			(layer "F.Fab")
		)
		(fp_line
			(start -0.12065 0.2794)
			(end -0.12065 0.3048)
			(stroke
				(width 0.1)
				(type default)
			)
			(layer "F.Fab")
		)
		(fp_line
			(start -0.12065 0.3048)
			(end -0.67945 0.3048)
			(stroke
				(width 0.1)
				(type default)
			)
			(layer "F.Fab")
		)
		(fp_line
			(start 0.120396 0.2794)
			(end -0.12065 0.2794)
			(stroke
				(width 0.1)
				(type default)
			)
			(layer "F.Fab")
		)
		(fp_line
			(start 0.120396 0.3048)
			(end 0.120396 0.2794)
			(stroke
				(width 0.1)
				(type default)
			)
			(layer "F.Fab")
		)
		(fp_line
			(start 0.12065 -0.3048)
			(end 0.67945 -0.3048)
			(stroke
				(width 0.1)
				(type default)
			)
			(layer "F.Fab")
		)
		(fp_line
			(start 0.12065 -0.2794)
			(end 0.12065 -0.3048)
			(stroke
				(width 0.1)
				(type default)
			)
			(layer "F.Fab")
		)
		(fp_line
			(start 0.67945 -0.3048)
			(end 0.67945 0.3048)
			(stroke
				(width 0.1)
				(type default)
			)
			(layer "F.Fab")
		)
		(fp_line
			(start 0.67945 0.3048)
			(end 0.120396 0.3048)
			(stroke
				(width 0.1)
				(type default)
			)
			(layer "F.Fab")
		)
		(pad "1" smd circle
			(at -0.40005 0)
			(size 0 0)
			(layers "F.Cu" "F.Mask" "F.Paste")
			(net "P0V9_RETIMER_CPU0_VMON")
		)
		(pad "2" smd circle
			(at 0.40005 0)
			(size 0 0)
			(layers "F.Cu" "F.Mask" "F.Paste")
			(net "GND")
		)
	)
)
